# S9S_MB_2U (Grand Teton) — schematic netlist excerpt (pin names and nets, part order shuffled) for the footprints in the layout excerpt that follows; sources: Cadence DE-HDL packaged netlist, KiCad conversion of 03242023_DA0F0TMBIJ0_F0T_Motherboard_J_brd_V01_OCP.brd

C500  Q_CAP  47UF 4V 20% X6S  pkg C0805  page 76 : A = PVCCFA_EHV_CPU0 ; B = GND
R1457  Q_RES  10K 1% CHIP  pkg 0402LF  page 200 : A = FM_XTAL_INPUT_FREQUENCY_1_MGPIO ; B = GND
C2297  Q_CAP  0.1UF 25V 10% EMPTY  pkg 0402  page 245 : A = FM_GPU_HSC_EN_BUF_R1 ; B = GND

(kicad_pcb
	(version 20260206)
	(generator "pcbnew")
	(generator_version "10.0")
	(general
		(thickness 1.6)
		(legacy_teardrops no)
	)
	(paper "A4")
	(title_block
		(title "03242023_DA0F0TMBIJ0_F0T_Motherboard_J_brd_V01_OCP.brd")
		(comment 1 "Grand Teton / footprints 5302-5304 of 6105")
	)
	(layers
		(0 "F.Cu" signal "TOP")
		(4 "In1.Cu" signal "GND")
		(6 "In2.Cu" signal "IN1")
		(8 "In3.Cu" signal "GND1")
		(10 "In4.Cu" signal "IN2")
		(12 "In5.Cu" signal "GND2")
		(14 "In6.Cu" signal "IN3")
		(16 "In7.Cu" signal "GND3")
		(18 "In8.Cu" signal "VCC")
		(20 "In9.Cu" signal "VCC1")
		(22 "In10.Cu" signal "GND4")
		(24 "In11.Cu" signal "IN4")
		(26 "In12.Cu" signal "GND5")
		(28 "In13.Cu" signal "IN5")
		(30 "In14.Cu" signal "GND6")
		(32 "In15.Cu" signal "IN6")
		(34 "In16.Cu" signal "GND7")
		(2 "B.Cu" signal "BOTTOM")
		(9 "F.Adhes" user "F.Adhesive")
		(11 "B.Adhes" user "B.Adhesive")
		(13 "F.Paste" user "Package Geometry/Pastemask Top")
		(15 "B.Paste" user "Package Geometry/Pastemask Bottom")
		(5 "F.SilkS" user "Ref Des/Silkscreen Top")
		(7 "B.SilkS" user "Ref Des/Silkscreen Bottom")
		(1 "F.Mask" user "Board Geometry/Soldermask Top")
		(3 "B.Mask" user "Board Geometry/Soldermask Bottom")
		(17 "Dwgs.User" user "User.Drawings")
		(19 "Cmts.User" user "User.Comments")
		(21 "Eco1.User" user "User.Eco1")
		(23 "Eco2.User" user "User.Eco2")
		(25 "Edge.Cuts" user "Board Geometry/Outline")
		(27 "Margin" user)
		(31 "F.CrtYd" user "Package Geometry/Place Bound Top")
		(29 "B.CrtYd" user "Package Geometry/Place Bound Bottom")
		(35 "F.Fab" user "Ref Des/Assembly Top")
		(33 "B.Fab" user "Ref Des/Assembly Bottom")
	)
	(footprint ""
		(layer "B.Cu")
		(at 352.402902 -210.19389)
		(property "Reference" "C500"
			(at 0 0 0)
			(layer "B.SilkS")
			(hide yes)
			(effects
				(font
					(size 1.27 1.27)
				)
				(justify mirror)
			)
		)
		(property "Value" ""
			(at 0 0 0)
			(layer "B.Fab")
			(effects
				(font
					(size 1.27 1.27)
				)
				(justify mirror)
			)
		)
		(duplicate_pad_numbers_are_jumpers no)
		(fp_line
			(start -1.524 -0.762)
			(end -1.524 0.762)
			(stroke
				(width 0.1524)
				(type default)
			)
			(layer "B.SilkS")
		)
		(fp_line
			(start -1.524 0.762)
			(end 1.524 0.762)
			(stroke
				(width 0.1524)
				(type default)
			)
			(layer "B.SilkS")
		)
		(fp_line
			(start 1.524 -0.762)
			(end -1.524 -0.762)
			(stroke
				(width 0.1524)
				(type default)
			)
			(layer "B.SilkS")
		)
		(fp_line
			(start 1.524 0.762)
			(end 1.524 -0.762)
			(stroke
				(width 0.1524)
				(type default)
			)
			(layer "B.SilkS")
		)
		(fp_line
			(start -1.1049 -0.724916)
			(end 1.1049 -0.724916)
			(stroke
				(width 0.1)
				(type default)
			)
			(layer "B.Fab")
		)
		(fp_line
			(start -1.1049 0.724916)
			(end -1.1049 -0.724916)
			(stroke
				(width 0.1)
				(type default)
			)
			(layer "B.Fab")
		)
		(fp_line
			(start 1.1049 -0.724916)
			(end 1.1049 0.724916)
			(stroke
				(width 0.1)
				(type default)
			)
			(layer "B.Fab")
		)
		(fp_line
			(start 1.1049 0.724916)
			(end -1.1049 0.724916)
			(stroke
				(width 0.1)
				(type default)
			)
			(layer "B.Fab")
		)
		(pad "1" smd rect
			(at 0.889 0)
			(size 1.016 1.27)
			(layers "B.Cu" "B.Mask" "B.Paste")
			(net "PVCCFA_EHV_CPU0")
		)
		(pad "2" smd rect
			(at -0.889 0)
			(size 1.016 1.27)
			(layers "B.Cu" "B.Mask" "B.Paste")
			(net "GND")
		)
	)
	(footprint ""
		(layer "B.Cu")
		(at 338.553044 -32.437578 90)
		(property "Reference" "R1457"
			(at 0 0 90)
			(layer "B.SilkS")
			(hide yes)
			(effects
				(font
					(size 1.27 1.27)
				)
				(justify mirror)
			)
		)
		(property "Value" ""
			(at 0 0 90)
			(layer "B.Fab")
			(effects
				(font
					(size 1.27 1.27)
				)
				(justify mirror)
			)
		)
		(duplicate_pad_numbers_are_jumpers no)
		(fp_line
			(start 0.7874 -0.4064)
			(end -0.7874 -0.4064)
			(stroke
				(width 0.1524)
				(type default)
			)
			(layer "B.SilkS")
		)
		(fp_line
			(start -0.7874 -0.4064)
			(end -0.7874 0.4064)
			(stroke
				(width 0.1524)
				(type default)
			)
			(layer "B.SilkS")
		)
		(fp_line
			(start 0.7874 0.4064)
			(end 0.7874 -0.4064)
			(stroke
				(width 0.1524)
				(type default)
			)
			(layer "B.SilkS")
		)
		(fp_line
			(start -0.7874 0.4064)
			(end 0.7874 0.4064)
			(stroke
				(width 0.1524)
				(type default)
			)
			(layer "B.SilkS")
		)
		(fp_line
			(start 0.67945 -0.305054)
			(end 0.12065 -0.305054)
			(stroke
				(width 0.1)
				(type default)
			)
			(layer "B.Fab")
		)
		(fp_line
			(start 0.12065 -0.305054)
			(end 0.12065 -0.2794)
			(stroke
				(width 0.1)
				(type default)
			)
			(layer "B.Fab")
		)
		(fp_line
			(start -0.12065 -0.3048)
			(end -0.67945 -0.3048)
			(stroke
				(width 0.1)
				(type default)
			)
			(layer "B.Fab")
		)
		(fp_line
			(start -0.67945 -0.3048)
			(end -0.67945 0.3048)
			(stroke
				(width 0.1)
				(type default)
			)
			(layer "B.Fab")
		)
		(fp_line
			(start 0.12065 -0.2794)
			(end -0.12065 -0.2794)
			(stroke
				(width 0.1)
				(type default)
			)
			(layer "B.Fab")
		)
		(fp_line
			(start -0.12065 -0.2794)
			(end -0.12065 -0.3048)
			(stroke
				(width 0.1)
				(type default)
			)
			(layer "B.Fab")
		)
		(fp_line
			(start 0.12065 0.2794)
			(end 0.12065 0.3048)
			(stroke
				(width 0.1)
				(type default)
			)
			(layer "B.Fab")
		)
		(fp_line
			(start -0.120396 0.2794)
			(end 0.12065 0.2794)
			(stroke
				(width 0.1)
				(type default)
			)
			(layer "B.Fab")
		)
		(fp_line
			(start 0.67945 0.3048)
			(end 0.67945 -0.305054)
			(stroke
				(width 0.1)
				(type default)
			)
			(layer "B.Fab")
		)
		(fp_line
			(start 0.12065 0.3048)
			(end 0.67945 0.3048)
			(stroke
				(width 0.1)
				(type default)
			)
			(layer "B.Fab")
		)
		(fp_line
			(start -0.120396 0.3048)
			(end -0.120396 0.2794)
			(stroke
				(width 0.1)
				(type default)
			)
			(layer "B.Fab")
		)
		(fp_line
			(start -0.67945 0.3048)
			(end -0.120396 0.3048)
			(stroke
				(width 0.1)
				(type default)
			)
			(layer "B.Fab")
		)
		(pad "1" smd circle
			(at 0.40005 0 270)
			(size 0 0)
			(layers "B.Cu" "B.Mask" "B.Paste")
			(net "FM_XTAL_INPUT_FREQUENCY_1_MGPIO")
		)
		(pad "2" smd circle
			(at -0.40005 0 270)
			(size 0 0)
			(layers "B.Cu" "B.Mask" "B.Paste")
			(net "GND")
		)
	)
	(footprint ""
		(layer "B.Cu")
		(at 238.30788 -422.976548 90)
		(property "Reference" "C2297"
			(at 0 0 90)
			(layer "B.SilkS")
			(hide yes)
			(effects
				(font
					(size 1.27 1.27)
				)
				(justify mirror)
			)
		)
		(property "Value" ""
			(at 0 0 90)
			(layer "B.Fab")
			(effects
				(font
					(size 1.27 1.27)
				)
				(justify mirror)
			)
		)
		(duplicate_pad_numbers_are_jumpers no)
		(fp_line
			(start 0.7874 -0.4064)
			(end -0.7874 -0.4064)
			(stroke
				(width 0.1524)
				(type default)
			)
			(layer "B.SilkS")
		)
		(fp_line
			(start -0.7874 -0.4064)
			(end -0.7874 0.4064)
			(stroke
				(width 0.1524)
				(type default)
			)
			(layer "B.SilkS")
		)
		(fp_line
			(start 0.7874 0.4064)
			(end 0.7874 -0.4064)
			(stroke
				(width 0.1524)
				(type default)
			)
			(layer "B.SilkS")
		)
		(fp_line
			(start -0.7874 0.4064)
			(end 0.7874 0.4064)
			(stroke
				(width 0.1524)
				(type default)
			)
			(layer "B.SilkS")
		)
		(fp_line
			(start 0.67945 -0.305054)
			(end 0.12065 -0.305054)
			(stroke
				(width 0.1)
				(type default)
			)
			(layer "B.Fab")
		)
		(fp_line
			(start 0.12065 -0.305054)
			(end 0.12065 -0.2794)
			(stroke
				(width 0.1)
				(type default)
			)
			(layer "B.Fab")
		)
		(fp_line
			(start -0.12065 -0.3048)
			(end -0.67945 -0.3048)
			(stroke
				(width 0.1)
				(type default)
			)
			(layer "B.Fab")
		)
		(fp_line
			(start -0.67945 -0.3048)
			(end -0.67945 0.3048)
			(stroke
				(width 0.1)
				(type default)
			)
			(layer "B.Fab")
		)
		(fp_line
			(start 0.12065 -0.2794)
			(end -0.12065 -0.2794)
			(stroke
				(width 0.1)
				(type default)
			)
			(layer "B.Fab")
		)
		(fp_line
			(start -0.12065 -0.2794)
			(end -0.12065 -0.3048)
			(stroke
				(width 0.1)
				(type default)
			)
			(layer "B.Fab")
		)
		(fp_line
			(start 0.12065 0.2794)
			(end 0.12065 0.3048)
			(stroke
				(width 0.1)
				(type default)
			)
			(layer "B.Fab")
		)
		(fp_line
			(start -0.120396 0.2794)
			(end 0.12065 0.2794)
			(stroke
				(width 0.1)
				(type default)
			)
			(layer "B.Fab")
		)
		(fp_line
			(start 0.67945 0.3048)
			(end 0.67945 -0.305054)
			(stroke
				(width 0.1)
				(type default)
			)
			(layer "B.Fab")
		)
		(fp_line
			(start 0.12065 0.3048)
			(end 0.67945 0.3048)
			(stroke
				(width 0.1)
				(type default)
			)
			(layer "B.Fab")
		)
		(fp_line
			(start -0.120396 0.3048)
			(end -0.120396 0.2794)
			(stroke
				(width 0.1)
				(type default)
			)
			(layer "B.Fab")
		)
		(fp_line
			(start -0.67945 0.3048)
			(end -0.120396 0.3048)
			(stroke
				(width 0.1)
				(type default)
			)
			(layer "B.Fab")
		)
		(pad "1" smd circle
			(at 0.40005 0 270)
			(size 0 0)
			(layers "B.Cu" "B.Mask" "B.Paste")
			(net "FM_GPU_HSC_EN_BUF_R1")
		)
		(pad "2" smd circle
			(at -0.40005 0 270)
			(size 0 0)
			(layers "B.Cu" "B.Mask" "B.Paste")
			(net "GND")
		)
	)
)
